# S9S_MB_2U (Grand Teton) — schematic netlist excerpt (pin names and nets, part order shuffled) for the footprints in the layout excerpt that follows; sources: Cadence DE-HDL packaged netlist, KiCad conversion of 03242023_DA0F0TMBIJ0_F0T_Motherboard_J_brd_V01_OCP.brd

C733  Q_CAP_DIFFBUS  DIFF BUS_0.22UF 6.3V 20% X6S  pkg C0201  page 176 : \1\ = P5E_CPU1_PE0_TX_C_DP<4> ; \2\ = P5E_CPU1_PE0_TX_DP<4>
PC1354  Q_CAP  0.1UF 25V 10% X7R  pkg 0402  page 279 : A = GND ; B = PVCCD_HV_CPU0_VREF
R4692  Q_RES  4.7K 1% EMPTY  pkg 0402LF  page 251 : A = P3V3_AUX ; B = TP_HSC_TYPE_ADC_ALERT

(kicad_pcb
	(version 20260206)
	(generator "pcbnew")
	(generator_version "10.0")
	(general
		(thickness 1.6)
		(legacy_teardrops no)
	)
	(paper "A4")
	(title_block
		(title "03242023_DA0F0TMBIJ0_F0T_Motherboard_J_brd_V01_OCP.brd")
		(comment 1 "Grand Teton / footprints 3683-3685 of 6105")
	)
	(layers
		(0 "F.Cu" signal "TOP")
		(4 "In1.Cu" signal "GND")
		(6 "In2.Cu" signal "IN1")
		(8 "In3.Cu" signal "GND1")
		(10 "In4.Cu" signal "IN2")
		(12 "In5.Cu" signal "GND2")
		(14 "In6.Cu" signal "IN3")
		(16 "In7.Cu" signal "GND3")
		(18 "In8.Cu" signal "VCC")
		(20 "In9.Cu" signal "VCC1")
		(22 "In10.Cu" signal "GND4")
		(24 "In11.Cu" signal "IN4")
		(26 "In12.Cu" signal "GND5")
		(28 "In13.Cu" signal "IN5")
		(30 "In14.Cu" signal "GND6")
		(32 "In15.Cu" signal "IN6")
		(34 "In16.Cu" signal "GND7")
		(2 "B.Cu" signal "BOTTOM")
		(9 "F.Adhes" user "F.Adhesive")
		(11 "B.Adhes" user "B.Adhesive")
		(13 "F.Paste" user "Package Geometry/Pastemask Top")
		(15 "B.Paste" user "Package Geometry/Pastemask Bottom")
		(5 "F.SilkS" user "Ref Des/Silkscreen Top")
		(7 "B.SilkS" user "Ref Des/Silkscreen Bottom")
		(1 "F.Mask" user "Board Geometry/Soldermask Top")
		(3 "B.Mask" user "Board Geometry/Soldermask Bottom")
		(17 "Dwgs.User" user "User.Drawings")
		(19 "Cmts.User" user "User.Comments")
		(21 "Eco1.User" user "User.Eco1")
		(23 "Eco2.User" user "User.Eco2")
		(25 "Edge.Cuts" user "Board Geometry/Outline")
		(27 "Margin" user)
		(31 "F.CrtYd" user "Package Geometry/Place Bound Top")
		(29 "B.CrtYd" user "Package Geometry/Place Bound Bottom")
		(35 "F.Fab" user "Ref Des/Assembly Top")
		(33 "B.Fab" user "Ref Des/Assembly Bottom")
	)
	(footprint ""
		(layer "F.Cu")
		(at 420.591488 -165.018974 180)
		(property "Reference" "PC1354"
			(at 0 0 180)
			(layer "F.SilkS")
			(hide yes)
			(effects
				(font
					(size 1.27 1.27)
				)
			)
		)
		(property "Value" ""
			(at 0 0 180)
			(layer "F.Fab")
			(effects
				(font
					(size 1.27 1.27)
				)
			)
		)
		(duplicate_pad_numbers_are_jumpers no)
		(fp_line
			(start 0.7874 0.4064)
			(end -0.7874 0.4064)
			(stroke
				(width 0.1524)
				(type default)
			)
			(layer "F.SilkS")
		)
		(fp_line
			(start 0.7874 -0.4064)
			(end 0.7874 0.4064)
			(stroke
				(width 0.1524)
				(type default)
			)
			(layer "F.SilkS")
		)
		(fp_line
			(start -0.7874 0.4064)
			(end -0.7874 -0.4064)
			(stroke
				(width 0.1524)
				(type default)
			)
			(layer "F.SilkS")
		)
		(fp_line
			(start -0.7874 -0.4064)
			(end 0.7874 -0.4064)
			(stroke
				(width 0.1524)
				(type default)
			)
			(layer "F.SilkS")
		)
		(fp_line
			(start 0.67945 0.3048)
			(end 0.120396 0.3048)
			(stroke
				(width 0.1)
				(type default)
			)
			(layer "F.Fab")
		)
		(fp_line
			(start 0.67945 -0.3048)
			(end 0.67945 0.3048)
			(stroke
				(width 0.1)
				(type default)
			)
			(layer "F.Fab")
		)
		(fp_line
			(start 0.12065 -0.2794)
			(end 0.12065 -0.3048)
			(stroke
				(width 0.1)
				(type default)
			)
			(layer "F.Fab")
		)
		(fp_line
			(start 0.12065 -0.3048)
			(end 0.67945 -0.3048)
			(stroke
				(width 0.1)
				(type default)
			)
			(layer "F.Fab")
		)
		(fp_line
			(start 0.120396 0.3048)
			(end 0.120396 0.2794)
			(stroke
				(width 0.1)
				(type default)
			)
			(layer "F.Fab")
		)
		(fp_line
			(start 0.120396 0.2794)
			(end -0.12065 0.2794)
			(stroke
				(width 0.1)
				(type default)
			)
			(layer "F.Fab")
		)
		(fp_line
			(start -0.12065 0.3048)
			(end -0.67945 0.3048)
			(stroke
				(width 0.1)
				(type default)
			)
			(layer "F.Fab")
		)
		(fp_line
			(start -0.12065 0.2794)
			(end -0.12065 0.3048)
			(stroke
				(width 0.1)
				(type default)
			)
			(layer "F.Fab")
		)
		(fp_line
			(start -0.12065 -0.2794)
			(end 0.12065 -0.2794)
			(stroke
				(width 0.1)
				(type default)
			)
			(layer "F.Fab")
		)
		(fp_line
			(start -0.12065 -0.305054)
			(end -0.12065 -0.2794)
			(stroke
				(width 0.1)
				(type default)
			)
			(layer "F.Fab")
		)
		(fp_line
			(start -0.67945 0.3048)
			(end -0.67945 -0.305054)
			(stroke
				(width 0.1)
				(type default)
			)
			(layer "F.Fab")
		)
		(fp_line
			(start -0.67945 -0.305054)
			(end -0.12065 -0.305054)
			(stroke
				(width 0.1)
				(type default)
			)
			(layer "F.Fab")
		)
		(pad "1" smd circle
			(at -0.40005 0 180)
			(size 0 0)
			(layers "F.Cu" "F.Mask" "F.Paste")
			(net "GND")
		)
		(pad "2" smd circle
			(at 0.40005 0 180)
			(size 0 0)
			(layers "F.Cu" "F.Mask" "F.Paste")
			(net "PVCCD_HV_CPU0_VREF")
		)
	)
	(footprint ""
		(layer "F.Cu")
		(at 294.045894 -413.05988)
		(property "Reference" "R4692"
			(at 0 0 0)
			(layer "F.SilkS")
			(hide yes)
			(effects
				(font
					(size 1.27 1.27)
				)
			)
		)
		(property "Value" ""
			(at 0 0 0)
			(layer "F.Fab")
			(effects
				(font
					(size 1.27 1.27)
				)
			)
		)
		(duplicate_pad_numbers_are_jumpers no)
		(fp_line
			(start -0.7874 -0.4064)
			(end 0.7874 -0.4064)
			(stroke
				(width 0.1524)
				(type default)
			)
			(layer "F.SilkS")
		)
		(fp_line
			(start -0.7874 0.4064)
			(end -0.7874 -0.4064)
			(stroke
				(width 0.1524)
				(type default)
			)
			(layer "F.SilkS")
		)
		(fp_line
			(start 0.7874 -0.4064)
			(end 0.7874 0.4064)
			(stroke
				(width 0.1524)
				(type default)
			)
			(layer "F.SilkS")
		)
		(fp_line
			(start 0.7874 0.4064)
			(end -0.7874 0.4064)
			(stroke
				(width 0.1524)
				(type default)
			)
			(layer "F.SilkS")
		)
		(fp_line
			(start -0.67945 -0.305054)
			(end -0.12065 -0.305054)
			(stroke
				(width 0.1)
				(type default)
			)
			(layer "F.Fab")
		)
		(fp_line
			(start -0.67945 0.3048)
			(end -0.67945 -0.305054)
			(stroke
				(width 0.1)
				(type default)
			)
			(layer "F.Fab")
		)
		(fp_line
			(start -0.12065 -0.305054)
			(end -0.12065 -0.2794)
			(stroke
				(width 0.1)
				(type default)
			)
			(layer "F.Fab")
		)
		(fp_line
			(start -0.12065 -0.2794)
			(end 0.12065 -0.2794)
			(stroke
				(width 0.1)
				(type default)
			)
			(layer "F.Fab")
		)
		(fp_line
			(start -0.12065 0.2794)
			(end -0.12065 0.3048)
			(stroke
				(width 0.1)
				(type default)
			)
			(layer "F.Fab")
		)
		(fp_line
			(start -0.12065 0.3048)
			(end -0.67945 0.3048)
			(stroke
				(width 0.1)
				(type default)
			)
			(layer "F.Fab")
		)
		(fp_line
			(start 0.120396 0.2794)
			(end -0.12065 0.2794)
			(stroke
				(width 0.1)
				(type default)
			)
			(layer "F.Fab")
		)
		(fp_line
			(start 0.120396 0.3048)
			(end 0.120396 0.2794)
			(stroke
				(width 0.1)
				(type default)
			)
			(layer "F.Fab")
		)
		(fp_line
			(start 0.12065 -0.3048)
			(end 0.67945 -0.3048)
			(stroke
				(width 0.1)
				(type default)
			)
			(layer "F.Fab")
		)
		(fp_line
			(start 0.12065 -0.2794)
			(end 0.12065 -0.3048)
			(stroke
				(width 0.1)
				(type default)
			)
			(layer "F.Fab")
		)
		(fp_line
			(start 0.67945 -0.3048)
			(end 0.67945 0.3048)
			(stroke
				(width 0.1)
				(type default)
			)
			(layer "F.Fab")
		)
		(fp_line
			(start 0.67945 0.3048)
			(end 0.120396 0.3048)
			(stroke
				(width 0.1)
				(type default)
			)
			(layer "F.Fab")
		)
		(pad "1" smd circle
			(at -0.40005 0)
			(size 0 0)
			(layers "F.Cu" "F.Mask" "F.Paste")
			(net "P3V3_AUX")
		)
		(pad "2" smd circle
			(at 0.40005 0)
			(size 0 0)
			(layers "F.Cu" "F.Mask" "F.Paste")
			(net "TP_HSC_TYPE_ADC_ALERT")
		)
	)
	(footprint ""
		(layer "F.Cu")
		(at 82.564478 -402.371052 -90)
		(property "Reference" "C733"
			(at 0 0 270)
			(layer "F.SilkS")
			(hide yes)
			(effects
				(font
					(size 1.27 1.27)
				)
			)
		)
		(property "Value" ""
			(at 0 0 270)
			(layer "F.Fab")
			(effects
				(font
					(size 1.27 1.27)
				)
			)
		)
		(duplicate_pad_numbers_are_jumpers no)
		(fp_line
			(start -0.299974 0.150114)
			(end -0.299974 -0.150114)
			(stroke
				(width 0.1)
				(type default)
			)
			(layer "F.Fab")
		)
		(fp_line
			(start 0.299974 0.150114)
			(end -0.299974 0.150114)
			(stroke
				(width 0.1)
				(type default)
			)
			(layer "F.Fab")
		)
		(fp_line
			(start -0.299974 -0.150114)
			(end 0.299974 -0.150114)
			(stroke
				(width 0.1)
				(type default)
			)
			(layer "F.Fab")
		)
		(fp_line
			(start 0.299974 -0.150114)
			(end 0.299974 0.150114)
			(stroke
				(width 0.1)
				(type default)
			)
			(layer "F.Fab")
		)
		(pad "1" smd rect
			(at -0.2667 0 270)
			(size 0.3048 0.381)
			(layers "F.Cu" "F.Mask" "F.Paste")
			(net "P5E_CPU1_PE0_TX_C_DP<4>")
		)
		(pad "2" smd rect
			(at 0.2667 0 270)
			(size 0.3048 0.381)
			(layers "F.Cu" "F.Mask" "F.Paste")
			(net "P5E_CPU1_PE0_TX_DP<4>")
		)
	)
)
